(kicad_pcb
	(version 20260206)
	(generator "pcbnew")
	(generator_version "10.0")
	(general
		(thickness 1.6)
		(legacy_teardrops no)
	)
	(paper "A4")
	(title_block
		(title "01162023_DA0F0TEBIF0_F0T_Expander_BD_F_brd_V02_OCP.brd")
		(comment 1 "Grand Teton / footprints 4264-4268 of 9728")
	)
	(layers
		(0 "F.Cu" signal "TOP")
		(4 "In1.Cu" signal "GND")
		(6 "In2.Cu" signal "VCC")
		(8 "In3.Cu" signal "VCC1")
		(10 "In4.Cu" signal "GND1")
		(12 "In5.Cu" signal "IN1")
		(14 "In6.Cu" signal "GND2")
		(16 "In7.Cu" signal "IN2")
		(18 "In8.Cu" signal "GND3")
		(20 "In9.Cu" signal "IN3")
		(22 "In10.Cu" signal "GND4")
		(24 "In11.Cu" signal "IN4")
		(26 "In12.Cu" signal "GND5")
		(28 "In13.Cu" signal "IN5")
		(30 "In14.Cu" signal "GND6")
		(32 "In15.Cu" signal "IN6")
		(34 "In16.Cu" signal "GND7")
		(2 "B.Cu" signal "BOTTOM")
		(9 "F.Adhes" user "F.Adhesive")
		(11 "B.Adhes" user "B.Adhesive")
		(13 "F.Paste" user "Package Geometry/Pastemask Top")
		(15 "B.Paste" user "Package Geometry/Pastemask Bottom")
		(5 "F.SilkS" user "Ref Des/Silkscreen Top")
		(7 "B.SilkS" user "Ref Des/Silkscreen Bottom")
		(1 "F.Mask" user "Board Geometry/Soldermask Top")
		(3 "B.Mask" user "Board Geometry/Soldermask Bottom")
		(17 "Dwgs.User" user "User.Drawings")
		(19 "Cmts.User" user "User.Comments")
		(21 "Eco1.User" user "User.Eco1")
		(23 "Eco2.User" user "User.Eco2")
		(25 "Edge.Cuts" user "Board Geometry/Outline")
		(27 "Margin" user)
		(31 "F.CrtYd" user "Package Geometry/Place Bound Top")
		(29 "B.CrtYd" user "Package Geometry/Place Bound Bottom")
		(35 "F.Fab" user "Ref Des/Assembly Top")
		(33 "B.Fab" user "Ref Des/Assembly Bottom")
	)
	(footprint ""
		(layer "F.Cu")
		(at 162.546538 -58.323734)
		(property "Reference" "PC379"
			(at 0 0 0)
			(layer "F.SilkS")
			(hide yes)
			(effects
				(font
					(size 1.27 1.27)
				)
			)
		)
		(property "Value" ""
			(at 0 0 0)
			(layer "F.Fab")
			(effects
				(font
					(size 1.27 1.27)
				)
			)
		)
		(duplicate_pad_numbers_are_jumpers no)
		(fp_line
			(start -1.524 -0.762)
			(end 1.524 -0.762)
			(stroke
				(width 0.1524)
				(type default)
			)
			(layer "F.SilkS")
		)
		(fp_line
			(start -1.524 0.762)
			(end -1.524 -0.762)
			(stroke
				(width 0.1524)
				(type default)
			)
			(layer "F.SilkS")
		)
		(fp_line
			(start 1.524 -0.762)
			(end 1.524 0.762)
			(stroke
				(width 0.1524)
				(type default)
			)
			(layer "F.SilkS")
		)
		(fp_line
			(start 1.524 0.762)
			(end -1.524 0.762)
			(stroke
				(width 0.1524)
				(type default)
			)
			(layer "F.SilkS")
		)
		(fp_line
			(start -1.1049 -0.724916)
			(end -1.1049 0.724916)
			(stroke
				(width 0.1)
				(type default)
			)
			(layer "F.Fab")
		)
		(fp_line
			(start -1.1049 0.724916)
			(end 1.1049 0.724916)
			(stroke
				(width 0.1)
				(type default)
			)
			(layer "F.Fab")
		)
		(fp_line
			(start 1.1049 -0.724916)
			(end -1.1049 -0.724916)
			(stroke
				(width 0.1)
				(type default)
			)
			(layer "F.Fab")
		)
		(fp_line
			(start 1.1049 0.724916)
			(end 1.1049 -0.724916)
			(stroke
				(width 0.1)
				(type default)
			)
			(layer "F.Fab")
		)
		(pad "1" smd rect
			(at -0.889 0 180)
			(size 1.016 1.27)
			(layers "F.Cu" "F.Mask" "F.Paste")
			(net "GND")
		)
		(pad "2" smd rect
			(at 0.889 0 180)
			(size 1.016 1.27)
			(layers "F.Cu" "F.Mask" "F.Paste")
			(net "P12V_AUX")
		)
	)
	(footprint ""
		(layer "F.Cu")
		(at 386.890768 8.142732 180)
		(property "Reference" "DE14T_1"
			(at 2.715768 3.061462 0)
			(unlocked yes)
			(layer "F.SilkS")
			(effects
				(font
					(size 0.7874 0.5842)
					(thickness 0.1524)
				)
				(justify left)
			)
		)
		(property "Value" ""
			(at 0 0 180)
			(layer "F.Fab")
			(effects
				(font
					(size 1.27 1.27)
				)
			)
		)
		(duplicate_pad_numbers_are_jumpers no)
		(fp_line
			(start 1.2192 2.1082)
			(end -1.2192 2.1082)
			(stroke
				(width 0.1524)
				(type default)
			)
			(layer "F.SilkS")
		)
		(fp_line
			(start 1.2192 -2.1082)
			(end 1.2192 2.1082)
			(stroke
				(width 0.1524)
				(type default)
			)
			(layer "F.SilkS")
		)
		(fp_line
			(start -1.2192 2.1082)
			(end -1.2192 -2.1082)
			(stroke
				(width 0.1524)
				(type default)
			)
			(layer "F.SilkS")
		)
		(fp_line
			(start -1.2192 -2.1082)
			(end 1.2192 -2.1082)
			(stroke
				(width 0.1524)
				(type default)
			)
			(layer "F.SilkS")
		)
		(pad "" np_thru_hole circle
			(at -2.8829 -1.27 90)
			(size 1.0414 1.0414)
			(drill 1.0414)
			(layers "*.Cu" "*.Mask")
			(clearance 0.381)
			(thermal_gap 0.381)
		)
		(pad "" np_thru_hole circle
			(at -2.8829 1.27 90)
			(size 1.0414 1.0414)
			(drill 1.0414)
			(layers "*.Cu" "*.Mask")
			(clearance 0.381)
			(thermal_gap 0.381)
		)
		(pad "" np_thru_hole circle
			(at 3.4671 -1.27 90)
			(size 1.0414 1.0414)
			(drill 1.0414)
			(layers "*.Cu" "*.Mask")
			(clearance 0.381)
			(thermal_gap 0.381)
		)
		(pad "" np_thru_hole circle
			(at 3.4671 1.27 90)
			(size 1.0414 1.0414)
			(drill 1.0414)
			(layers "*.Cu" "*.Mask")
			(clearance 0.381)
			(thermal_gap 0.381)
		)
		(pad "1" smd rect
			(at 0.8255 -0.249936 90)
			(size 0.3048 0.508)
			(layers "F.Cu" "F.Mask" "F.Paste")
			(net "85_10INCH_IN2_DP")
		)
		(pad "2" smd rect
			(at 0.8255 0.249936 90)
			(size 0.3048 0.508)
			(layers "F.Cu" "F.Mask" "F.Paste")
			(net "85_10INCH_IN2_DN")
		)
		(pad "3" smd circle
			(at 0 0 180)
			(size 0 0)
			(layers "F.Cu" "F.Mask" "F.Paste")
			(net "COUPON_GND2")
		)
		(zone
			(layer "F.Cu")
			(hatch none 0.5)
			(connect_pads
				(clearance 0)
			)
			(min_thickness 0.25)
			(keepout
				(tracks not_allowed)
				(vias allowed)
				(pads allowed)
				(copperpour not_allowed)
				(footprints allowed)
			)
			(placement
				(enabled no)
				(sheetname "")
			)
			(fill
				(thermal_gap 0.5)
				(thermal_bridge_width 0.5)
				(island_removal_mode 0)
			)
			(polygon
				(pts
					(xy 385.773168 8.691372) (xy 385.773168 8.595868) (xy 386.370068 8.595868) (xy 386.370068 8.189468)
					(xy 385.773168 8.189468) (xy 385.773168 8.095996) (xy 386.370068 8.095996) (xy 386.370068 7.689596)
					(xy 385.773168 7.689596) (xy 385.773168 7.594092) (xy 386.471668 7.594092) (xy 386.471668 8.691372)
				)
			)
		)
		(zone
			(layers "F.Cu" "B.Cu" "In1.Cu" "In2.Cu" "In3.Cu" "In4.Cu" "In5.Cu" "In6.Cu"
				"In7.Cu" "In8.Cu" "In9.Cu" "In10.Cu" "In11.Cu" "In12.Cu" "In13.Cu" "In14.Cu"
				"In15.Cu" "In16.Cu"
			)
			(hatch none 0.5)
			(connect_pads
				(clearance 0)
			)
			(min_thickness 0.25)
			(keepout
				(tracks not_allowed)
				(vias allowed)
				(pads allowed)
				(copperpour not_allowed)
				(footprints allowed)
			)
			(placement
				(enabled no)
				(sheetname "")
			)
			(fill
				(thermal_gap 0.5)
				(thermal_bridge_width 0.5)
				(island_removal_mode 0)
			)
			(polygon
				(pts
					(arc
						(start 384.350768 6.872732)
						(mid 382.496568 6.872732)
						(end 384.350768 6.872732)
					)
				)
			)
		)
		(zone
			(layers "F.Cu" "B.Cu" "In1.Cu" "In2.Cu" "In3.Cu" "In4.Cu" "In5.Cu" "In6.Cu"
				"In7.Cu" "In8.Cu" "In9.Cu" "In10.Cu" "In11.Cu" "In12.Cu" "In13.Cu" "In14.Cu"
				"In15.Cu" "In16.Cu"
			)
			(hatch none 0.5)
			(connect_pads
				(clearance 0)
			)
			(min_thickness 0.25)
			(keepout
				(tracks not_allowed)
				(vias allowed)
				(pads allowed)
				(copperpour not_allowed)
				(footprints allowed)
			)
			(placement
				(enabled no)
				(sheetname "")
			)
			(fill
				(thermal_gap 0.5)
				(thermal_bridge_width 0.5)
				(island_removal_mode 0)
			)
			(polygon
				(pts
					(arc
						(start 384.350768 9.412732)
						(mid 382.496568 9.412732)
						(end 384.350768 9.412732)
					)
				)
			)
		)
		(zone
			(layers "F.Cu" "B.Cu" "In1.Cu" "In2.Cu" "In3.Cu" "In4.Cu" "In5.Cu" "In6.Cu"
				"In7.Cu" "In8.Cu" "In9.Cu" "In10.Cu" "In11.Cu" "In12.Cu" "In13.Cu" "In14.Cu"
				"In15.Cu" "In16.Cu"
			)
			(hatch none 0.5)
			(connect_pads
				(clearance 0)
			)
			(min_thickness 0.25)
			(keepout
				(tracks not_allowed)
				(vias allowed)
				(pads allowed)
				(copperpour not_allowed)
				(footprints allowed)
			)
			(placement
				(enabled no)
				(sheetname "")
			)
			(fill
				(thermal_gap 0.5)
				(thermal_bridge_width 0.5)
				(island_removal_mode 0)
			)
			(polygon
				(pts
					(arc
						(start 390.700768 6.872732)
						(mid 388.846568 6.872732)
						(end 390.700768 6.872732)
					)
				)
			)
		)
		(zone
			(layers "F.Cu" "B.Cu" "In1.Cu" "In2.Cu" "In3.Cu" "In4.Cu" "In5.Cu" "In6.Cu"
				"In7.Cu" "In8.Cu" "In9.Cu" "In10.Cu" "In11.Cu" "In12.Cu" "In13.Cu" "In14.Cu"
				"In15.Cu" "In16.Cu"
			)
			(hatch none 0.5)
			(connect_pads
				(clearance 0)
			)
			(min_thickness 0.25)
			(keepout
				(tracks not_allowed)
				(vias allowed)
				(pads allowed)
				(copperpour not_allowed)
				(footprints allowed)
			)
			(placement
				(enabled no)
				(sheetname "")
			)
			(fill
				(thermal_gap 0.5)
				(thermal_bridge_width 0.5)
				(island_removal_mode 0)
			)
			(polygon
				(pts
					(arc
						(start 390.700768 9.412732)
						(mid 388.846568 9.412732)
						(end 390.700768 9.412732)
					)
				)
			)
		)
	)
	(footprint ""
		(layer "F.Cu")
		(at 181.728872 -343.952322 90)
		(property "Reference" "C384"
			(at 0 0 90)
			(layer "F.SilkS")
			(hide yes)
			(effects
				(font
					(size 1.27 1.27)
				)
			)
		)
		(property "Value" ""
			(at 0 0 90)
			(layer "F.Fab")
			(effects
				(font
					(size 1.27 1.27)
				)
			)
		)
		(duplicate_pad_numbers_are_jumpers no)
		(fp_line
			(start 0.299974 -0.150114)
			(end 0.299974 0.150114)
			(stroke
				(width 0.1)
				(type default)
			)
			(layer "F.Fab")
		)
		(fp_line
			(start -0.299974 -0.150114)
			(end 0.299974 -0.150114)
			(stroke
				(width 0.1)
				(type default)
			)
			(layer "F.Fab")
		)
		(fp_line
			(start 0.299974 0.150114)
			(end -0.299974 0.150114)
			(stroke
				(width 0.1)
				(type default)
			)
			(layer "F.Fab")
		)
		(fp_line
			(start -0.299974 0.150114)
			(end -0.299974 -0.150114)
			(stroke
				(width 0.1)
				(type default)
			)
			(layer "F.Fab")
		)
		(pad "1" smd rect
			(at -0.2667 0 90)
			(size 0.3048 0.381)
			(layers "F.Cu" "F.Mask" "F.Paste")
			(net "P5E_PEX1_STN7_TX_DP<121>")
		)
		(pad "2" smd rect
			(at 0.2667 0 90)
			(size 0.3048 0.381)
			(layers "F.Cu" "F.Mask" "F.Paste")
			(net "P5E_PEX1_STN7_TX_C_DP<121>")
		)
	)
	(footprint ""
		(layer "F.Cu")
		(at 116.985796 -318.514984 90)
		(property "Reference" "R6460"
			(at 0 0 90)
			(layer "F.SilkS")
			(hide yes)
			(effects
				(font
					(size 1.27 1.27)
				)
			)
		)
		(property "Value" ""
			(at 0 0 90)
			(layer "F.Fab")
			(effects
				(font
					(size 1.27 1.27)
				)
			)
		)
		(duplicate_pad_numbers_are_jumpers no)
		(fp_line
			(start 0.7874 -0.4064)
			(end 0.7874 0.4064)
			(stroke
				(width 0.1524)
				(type default)
			)
			(layer "F.SilkS")
		)
		(fp_line
			(start -0.7874 -0.4064)
			(end 0.7874 -0.4064)
			(stroke
				(width 0.1524)
				(type default)
			)
			(layer "F.SilkS")
		)
		(fp_line
			(start 0.7874 0.4064)
			(end -0.7874 0.4064)
			(stroke
				(width 0.1524)
				(type default)
			)
			(layer "F.SilkS")
		)
		(fp_line
			(start -0.7874 0.4064)
			(end -0.7874 -0.4064)
			(stroke
				(width 0.1524)
				(type default)
			)
			(layer "F.SilkS")
		)
		(fp_line
			(start -0.12065 -0.305054)
			(end -0.12065 -0.2794)
			(stroke
				(width 0.1)
				(type default)
			)
			(layer "F.Fab")
		)
		(fp_line
			(start -0.67945 -0.305054)
			(end -0.12065 -0.305054)
			(stroke
				(width 0.1)
				(type default)
			)
			(layer "F.Fab")
		)
		(fp_line
			(start 0.67945 -0.3048)
			(end 0.67945 0.3048)
			(stroke
				(width 0.1)
				(type default)
			)
			(layer "F.Fab")
		)
		(fp_line
			(start 0.12065 -0.3048)
			(end 0.67945 -0.3048)
			(stroke
				(width 0.1)
				(type default)
			)
			(layer "F.Fab")
		)
		(fp_line
			(start 0.12065 -0.2794)
			(end 0.12065 -0.3048)
			(stroke
				(width 0.1)
				(type default)
			)
			(layer "F.Fab")
		)
		(fp_line
			(start -0.12065 -0.2794)
			(end 0.12065 -0.2794)
			(stroke
				(width 0.1)
				(type default)
			)
			(layer "F.Fab")
		)
		(fp_line
			(start 0.120396 0.2794)
			(end -0.12065 0.2794)
			(stroke
				(width 0.1)
				(type default)
			)
			(layer "F.Fab")
		)
		(fp_line
			(start -0.12065 0.2794)
			(end -0.12065 0.3048)
			(stroke
				(width 0.1)
				(type default)
			)
			(layer "F.Fab")
		)
		(fp_line
			(start 0.67945 0.3048)
			(end 0.120396 0.3048)
			(stroke
				(width 0.1)
				(type default)
			)
			(layer "F.Fab")
		)
		(fp_line
			(start 0.120396 0.3048)
			(end 0.120396 0.2794)
			(stroke
				(width 0.1)
				(type default)
			)
			(layer "F.Fab")
		)
		(fp_line
			(start -0.12065 0.3048)
			(end -0.67945 0.3048)
			(stroke
				(width 0.1)
				(type default)
			)
			(layer "F.Fab")
		)
		(fp_line
			(start -0.67945 0.3048)
			(end -0.67945 -0.305054)
			(stroke
				(width 0.1)
				(type default)
			)
			(layer "F.Fab")
		)
		(pad "1" smd circle
			(at -0.40005 0 90)
			(size 0 0)
			(layers "F.Cu" "F.Mask" "F.Paste")
			(net "P0V8_SERDES_VDDA_PEX0")
		)
		(pad "2" smd circle
			(at 0.40005 0 90)
			(size 0 0)
			(layers "F.Cu" "F.Mask" "F.Paste")
			(net "P0V8_SERDES_VDDA_PEX0_C11")
		)
	)
	(footprint ""
		(layer "F.Cu")
		(at 189.88786 -414.581086 -90)
		(property "Reference" "R6780"
			(at 0 0 270)
			(layer "F.SilkS")
			(hide yes)
			(effects
				(font
					(size 1.27 1.27)
				)
			)
		)
		(property "Value" ""
			(at 0 0 270)
			(layer "F.Fab")
			(effects
				(font
					(size 1.27 1.27)
				)
			)
		)
		(duplicate_pad_numbers_are_jumpers no)
		(fp_line
			(start -0.7874 0.4064)
			(end -0.7874 -0.4064)
			(stroke
				(width 0.1524)
				(type default)
			)
			(layer "F.SilkS")
		)
		(fp_line
			(start 0.7874 0.4064)
			(end -0.7874 0.4064)
			(stroke
				(width 0.1524)
				(type default)
			)
			(layer "F.SilkS")
		)
		(fp_line
			(start -0.7874 -0.4064)
			(end 0.7874 -0.4064)
			(stroke
				(width 0.1524)
				(type default)
			)
			(layer "F.SilkS")
		)
		(fp_line
			(start 0.7874 -0.4064)
			(end 0.7874 0.4064)
			(stroke
				(width 0.1524)
				(type default)
			)
			(layer "F.SilkS")
		)
		(fp_line
			(start -0.67945 0.3048)
			(end -0.67945 -0.305054)
			(stroke
				(width 0.1)
				(type default)
			)
			(layer "F.Fab")
		)
		(fp_line
			(start -0.12065 0.3048)
			(end -0.67945 0.3048)
			(stroke
				(width 0.1)
				(type default)
			)
			(layer "F.Fab")
		)
		(fp_line
			(start 0.120396 0.3048)
			(end 0.120396 0.2794)
			(stroke
				(width 0.1)
				(type default)
			)
			(layer "F.Fab")
		)
		(fp_line
			(start 0.67945 0.3048)
			(end 0.120396 0.3048)
			(stroke
				(width 0.1)
				(type default)
			)
			(layer "F.Fab")
		)
		(fp_line
			(start -0.12065 0.2794)
			(end -0.12065 0.3048)
			(stroke
				(width 0.1)
				(type default)
			)
			(layer "F.Fab")
		)
		(fp_line
			(start 0.120396 0.2794)
			(end -0.12065 0.2794)
			(stroke
				(width 0.1)
				(type default)
			)
			(layer "F.Fab")
		)
		(fp_line
			(start -0.12065 -0.2794)
			(end 0.12065 -0.2794)
			(stroke
				(width 0.1)
				(type default)
			)
			(layer "F.Fab")
		)
		(fp_line
			(start 0.12065 -0.2794)
			(end 0.12065 -0.3048)
			(stroke
				(width 0.1)
				(type default)
			)
			(layer "F.Fab")
		)
		(fp_line
			(start 0.12065 -0.3048)
			(end 0.67945 -0.3048)
			(stroke
				(width 0.1)
				(type default)
			)
			(layer "F.Fab")
		)
		(fp_line
			(start 0.67945 -0.3048)
			(end 0.67945 0.3048)
			(stroke
				(width 0.1)
				(type default)
			)
			(layer "F.Fab")
		)
		(fp_line
			(start -0.67945 -0.305054)
			(end -0.12065 -0.305054)
			(stroke
				(width 0.1)
				(type default)
			)
			(layer "F.Fab")
		)
		(fp_line
			(start -0.12065 -0.305054)
			(end -0.12065 -0.2794)
			(stroke
				(width 0.1)
				(type default)
			)
			(layer "F.Fab")
		)
		(pad "1" smd circle
			(at -0.40005 0 270)
			(size 0 0)
			(layers "F.Cu" "F.Mask" "F.Paste")
			(net "P12V_AUX_FP_TRIGGER")
		)
		(pad "2" smd circle
			(at 0.40005 0 270)
			(size 0 0)
			(layers "F.Cu" "F.Mask" "F.Paste")
			(net "GND")
		)
	)
)
